# Lightning_PTB_BOM.xlsx — Primary and Alternate BOM of 55 (bom)
| Level | Parent Number | Part Number | Description | Green Factor | Life Cycle State | Manufacturer | Manufacturer Part Number | Source | BOM Usage | M/P Code | S/D | Qty | UoM | Location |
| 1 | 55.B0714.D01G | 022.40008.0011 | SW PUSH BUTTON 3P MS-B1PL-10 DIP ,PA66 | R2_SA; | Released | WELLBUYING | MS-B1PL-10 | Single |  | Purchase | DIP | 1 | PCS | SW1 |
| 1 | 55.B0714.D01G | 20.81942.024 | CONN CTR 4P+20S RT 51939-689LF ,PA66 | R2_SA; | Released | FCI | 51939-689LF | Single |  | Purchase | DIP | 1 | PCS | CN4 |
| 1 | 55.B0714.D01G | 55.B0714.S01G | Lightning PTB (S) GCE-1A | N/A; | Released |  |  |  | E | Manufacture | DIP | 1 | PCS |  |
| 2 | 55.B0714.S01G | 48.64W23.01A | PCB 14629-1A Lightning PTB CARD 4L GC | R2_C; | Released | GCE |  | Single |  | Purchase | SMT | 1 | PCS |  |
| 2 | 55.B0714.S01G | 63.00000.00L | CHIP RES 0 J 1/10W 0603 | R2_SA;HF_SA;G_SA; | Released | TA-I ; RALEC ; YAGEO ; WALSIN | RM06JTN0 ; RTT03000JTP ; RC0603JR-070RL ; WR06X000PTL | Multiple |  | Purchase | SMT | 1 | PCS | PR65 |
| 2 | 55.B0714.S01G | 63.68031.16L | CHIP RES 68 J 1/8W 0805 | R2_SA;HF_SA;G_SA; | Released | RALEC ; TA-I ; YAGEO | RTT05680JTP ; RM10JTN680 ; RC0805JR-0768RL | Multiple |  | Purchase | SMT | 1 | PCS | R378 |
| 2 | 55.B0714.S01G | 63.R0034.1DL | CHIP RES 0 J 1/16W 0402 | R2_SA;HF_SA;G_SA; | Released | TA-I;RALEC;CYNTEC;YAGEO;WALSIN | RM04JTN0;RTT02000JTH;RR0510X-000-XN;RC0402JR-070RL;WR04X000PTL | Multiple |  | Purchase | SMT | 12 | PCS | R366 R384 R385 R386 R387 R388 R389 R390 R391 R480 R481 R482 |
| 2 | 55.B0714.S01G | 64.10005.6DL | CHIP RES 100 F 1/16W 0402 | R2_SA;HF_SA;G_SA; | Released | TA-I ; RALEC ; CYNTEC ; YAGEO;WALSIN | RM04FTN1000 ; RTT021000FTH ; RR0510S-1000-FN ; RC0402FR-07100RL;WR04X1000FTL | Multiple |  | Purchase | SMT | 1 | PCS | R375 |
| 2 | 55.B0714.S01G | 64.10025.6DL | CHIP RES 10K F 1/16W 0402 | R2_SA;HF_SA;G_SA; | Released | TA-I;RALEC;CYNTEC;YAGEO;WALSIN | RM04FTN1002 ; RTT021002FTH ; RR0510S-103-FN ; RC0402FR-0710KL;WR04X1002FTL | Multiple |  | Purchase | SMT | 5 | PCS | R342 R343 R344 R353 R379 |
| 2 | 55.B0714.S01G | 64.10035.6DL | CHIP RES 100K F 1/16W 0402 | R2_SA;HF_SA;G_SA; | Released | TA-I;RALEC;CYNTEC;YAGEO;WALSIN | RM04FTN1003 ; RTT021003FTH ; RR0510S-104-FN ; RC0402FR-07100KL;WR04X1003FTL | Multiple |  | Purchase | SMT | 1 | PCS | R376 |
| 2 | 55.B0714.S01G | 64.20015.55L | CHIP RES 2K F 1/10W 0603 | R2_SA;HF_SA;G_SA; | Released | TA-I ; RALEC ; YAGEO;WALSIN | RM06FTN2001 ; RTT032001FTP ; RC0603FR-072KL;WR06X2001FTL | Multiple |  | Purchase | SMT | 1 | PCS | R483 |
| 2 | 55.B0714.S01G | 64.47035.6DL | CHIP RES 470K F 1/16W 0402 | R2_SA;HF_SA;G_SA; | Released | TA-I;RALEC;CYNTEC;YAGEO;WALSIN | RM04FTN4703;RTT024703FTH;RR0510S-474-FN;RC0402FR-07470KL;WR04X4703FTL | Multiple |  | Purchase | SMT | 1 | PCS | R374 |
| 2 | 55.B0714.S01G | 71.P9511.00W | IC BUF PCA9511ADP-T TSSOP 8P | R2_SA; | Released | NXP | PCA9511ADP-T | Single |  | Purchase | SMT | 1 | PCS | U51 |
| 2 | 55.B0714.S01G | 75.00325.010 | XTOR PHOTO SFH325-3 SMD BJ | R2_SA; | Released | OSRAM | SFH325-3 | Single |  | Purchase | SMT | 1 | PCS | Q31 |
| 2 | 55.B0714.S01G | 75.00426.010 | LED IR EMITT SFH426 SMD | R2_SA; | Released | OSRAM | SFH426 | Single |  | Purchase | SMT | 1 | PCS | LED16 |
| 2 | 55.B0714.S01G | 77.26861.05L | CHIP CAP POS 68U 16V M7343 ESR | R2_SA; | Released | SANYO | 16TQC68MY | Single |  | Purchase | SMT | 3 | PCS | TC3 TC4 TC5 |
| 2 | 55.B0714.S01G | 78.10324.2FL | CHIP CAP C 0.01U 50V K0402 X7R | R2_SA;HF_SA;G_SA; | Released | MURATA;PHYCOMP;DARFON;TDK;SAMSUNG;WALSIN;MURATA | GRM155R71H103KA88D;223858715636;C1005X7R103KGT;C1005X7R1H103KT;CL05B103KB5NNNC;0402B103K500CT;WBM155R71H103KA01D | Multiple |  | Purchase | SMT | 1 | PCS | C345 |
| 2 | 55.B0714.S01G | 78.10424.2BL | CHIP CAP C 0.1U 50V K0603 X7R | R2_SA;HF_SA;G_SA; | Released | MURATA;TDK;AVX;PHYCOMP;SAMSUNG;DARFON;MATSUKI;WALSIN | GRM188R71H104KA93D;C1608X7R1H104KT000N;06035C104KAT2A;223858615649;CL10B104KB8NNNC;C1608X7R104KGT;MAG03X7R1H104K;0603B104K500CT | Multiple |  | Purchase | SMT | 1 | PCS | C344 |
| 2 | 55.B0714.S01G | 78.10622.51L | CHIP CAP C 10U 25V K0805 X5R | R2_SA;HF_SA;G_SA; | Released | MATSUKI;SAMSUNG;TAIYO;AVX;MURATA;TDK;YAGEO | MAG05X5R1E106K;CL21A106KAYNNNE;TMK212BJ106KG-TD;CM21X5R106K25AT;GRM21BR61E106KA73L;C2012X5R1E106KT;CC0805KKX5R8BB106 | Multiple |  | Purchase | SMT | 3 | PCS | C348 C349 C355 |
| 2 | 55.B0714.S01G | 83.00191.K70 | LED GREEN LTST-C191KGKT-5A SMD | R2_SA;HF_SA; | Released | LITEON | LTST-C191KGKT-5A | Single |  | Purchase | SMT | 1 | PCS | LED1 |
| 2 | 55.B0714.S01G | 84.02222.V11 | XTOR MMBT2222A NPN SOT-23 | R2_SA;HF_SA;G_SA; | Released | PANJIT | MMBT2222A | Single |  | Purchase | SMT | 1 | PCS | Q33 |
| 2 | 55.B0714.S01G | 84.27002.W31 | FET MOS 2N7002 NC SOT-23 | R2_SA;HF_SA;G_SA; | Released | PANJIT | 2N7002 | Single |  | Purchase | SMT | 1 | PCS | Q34 |
| 1 | 55.B0714.D01G | 60.B0729.001 | ASSY PTB MAYLAR HB | R2_C; | Released | TBD |  | Single | M | Purchase | DIP | 1 | PCS |  |
| 1 | 55.B0714.D01G | 86.00Q43.140 | SCRW NUT HEX M3 | R_SA;G_SA; | Released | TBD |  | Single |  | Purchase | DIP | 2 | PCS |  |
| 1 | 55.B0714.D01G | 86.1A524.100 | SCRW MACH PAN M3*10L | R_SA; | Released | TBD |  | Single |  | Purchase | DIP | 2 | PCS |  |
